#ISCELL
  mstr_symbols intel_corp_bpage *
  *
#CELL
  mstr_discrete cap *
  page149_i1
#CELL
  mstr_discrete cap *
  page149_i100
#CELL
  mstr_discrete cap *
  page149_i101
#CELL
  mstr_discrete cap *
  page149_i102
#CELL
  mstr_discrete cap *
  page149_i103
#CELL
  mstr_discrete cap *
  page149_i104
#CELL
  mstr_discrete cap *
  page149_i105
#CELL
  mstr_discrete cap *
  page149_i106
#CELL
  mstr_discrete cap *
  page149_i107
#CELL
  mstr_discrete cap *
  page149_i108
#CELL
  mstr_discrete cap *
  page149_i109
#CELL
  mstr_discrete cap *
  page149_i110
#CELL
  mstr_discrete cap *
  page149_i112
#CELL
  mstr_discrete cap *
  page149_i113
#CELL
  mstr_discrete cap *
  page149_i114
#CELL
  mstr_discrete cap *
  page149_i115
#CELL
  mstr_discrete cap *
  page149_i116
#CELL
  mstr_discrete cap *
  page149_i117
#CELL
  mstr_discrete cap *
  page149_i118
#CELL
  dev_discrete cap_a *
  page149_i119
#CELL
  dev_discrete cap_a *
  page149_i120
#CELL
  dev_discrete cap_a *
  page149_i121
#CELL
  dev_discrete cap_a *
  page149_i122
#CELL
  dev_discrete cap_a *
  page149_i123
#CELL
  dev_discrete cap_a *
  page149_i124
#CELL
  dev_discrete cap_a *
  page149_i125
#CELL
  dev_discrete cap_a *
  page149_i126
#CELL
  dev_discrete cap_a *
  page149_i128
#CELL
  mstr_discrete cap *
  page149_i129
#CELL
  mstr_discrete cap *
  page149_i130
#ISCELL
  mstr_symbols p3v3_stby *
  page149_i14
#ISCELL
  w_power w_vcc_circle *
  page149_i16
#CELL
  mstr_discrete cap *
  page149_i17
#ISCELL
  mstr_symbols gnd *
  page149_i18
#ISCELL
  w_power w_vcc_circle *
  page149_i2
#CELL
  w_hdl hcb1608kf-800t30-gp *
  page149_i22
#ISCELL
  mstr_symbols p3v3_stby *
  page149_i23
#ISCELL
  mstr_symbols gnd *
  page149_i24
#CELL
  mstr_discrete cap *
  page149_i25
#ISCELL
  w_power w_vcc_circle *
  page149_i26
#ISCELL
  mstr_symbols gnd *
  page149_i27
#ISCELL
  w_power w_vcc_circle *
  page149_i29
#CELL
  mstr_discrete cap *
  page149_i31
#ISCELL
  mstr_symbols gnd *
  page149_i32
#ISCELL
  mstr_symbols gnd *
  page149_i4
#CELL
  mstr_discrete cap *
  page149_i40
#ISCELL
  mstr_symbols gnd *
  page149_i41
#CELL
  w_hdl hcb1608kf-800t30-gp *
  page149_i42
#ISCELL
  w_power w_vcc_circle *
  page149_i43
#ISCELL
  mstr_symbols p3v3_stby *
  page149_i44
#ISCELL
  w_power w_vcc_circle *
  page149_i45
#CELL
  mstr_discrete cap *
  page149_i46
#ISCELL
  mstr_symbols gnd *
  page149_i49
#CELL
  mstr_discrete cap *
  page149_i5
#CELL
  mstr_discrete cap *
  page149_i50
#CELL
  mstr_discrete cap *
  page149_i51
#ISCELL
  mstr_symbols p3v3_stby *
  page149_i54
#ISCELL
  mstr_symbols gnd *
  page149_i55
#ISCELL
  w_power w_vcc_circle *
  page149_i62
#ISCELL
  mstr_symbols p3v3_stby *
  page149_i65
#ISCELL
  w_power w_vcc_circle *
  page149_i66
#ISCELL
  mstr_symbols gnd *
  page149_i68
#ISCELL
  w_power w_vcc_circle *
  page149_i69
#ISCELL
  mstr_symbols gnd *
  page149_i7
#ISCELL
  w_power w_vcc_circle *
  page149_i78
#CELL
  mstr_discrete cap *
  page149_i79
#ISCELL
  mstr_symbols gnd *
  page149_i80
#ISCELL
  mstr_symbols p3v3_stby *
  page149_i84
#CELL
  w_hdl hcb1608kf-800t30-gp *
  page149_i85
#CELL
  w_hdl hcb1608kf-800t30-gp *
  page149_i86
#ISCELL
  mstr_symbols p3v3_stby *
  page149_i87
#CELL
  w_hdl hcb1608kf-800t30-gp *
  page149_i88
#ISCELL
  mstr_symbols p3v3_stby *
  page149_i89
#CELL
  mstr_discrete res *
  page149_i90
#CELL
  mstr_discrete res *
  page149_i91
#CELL
  mstr_discrete cap *
  page149_i92
#CELL
  mstr_discrete cap *
  page149_i93
#CELL
  mstr_discrete cap *
  page149_i95
#CELL
  mstr_discrete cap *
  page149_i96
#CELL
  mstr_discrete cap *
  page149_i97
#CELL
  mstr_discrete cap *
  page149_i98
#CELL
  mstr_discrete cap *
  page149_i99
